(kicad_pcb
	(version 20260206)
	(generator "pcbnew")
	(generator_version "10.0")
	(general
		(thickness 1.6)
		(legacy_teardrops no)
	)
	(paper "A4")
	(title_block
		(title "12092022_DA0F0TMDCD0_F0T_Management_Board_D_brd_V3_OCP.brd")
		(comment 1 "Grand Teton / footprints 599-604 of 1440")
	)
	(layers
		(0 "F.Cu" signal "TOP")
		(4 "In1.Cu" signal "GND")
		(6 "In2.Cu" signal "IN1")
		(8 "In3.Cu" signal "GND1")
		(10 "In4.Cu" signal "IN2")
		(12 "In5.Cu" signal "VCC")
		(14 "In6.Cu" signal "VCC1")
		(16 "In7.Cu" signal "IN3")
		(18 "In8.Cu" signal "GND2")
		(20 "In9.Cu" signal "IN4")
		(22 "In10.Cu" signal "GND3")
		(2 "B.Cu" signal "BOTTOM")
		(9 "F.Adhes" user "F.Adhesive")
		(11 "B.Adhes" user "B.Adhesive")
		(13 "F.Paste" user "Package Geometry/Pastemask Top")
		(15 "B.Paste" user "Package Geometry/Pastemask Bottom")
		(5 "F.SilkS" user "Ref Des/Silkscreen Top")
		(7 "B.SilkS" user "Ref Des/Silkscreen Bottom")
		(1 "F.Mask" user "Board Geometry/Soldermask Top")
		(3 "B.Mask" user "Board Geometry/Soldermask Bottom")
		(17 "Dwgs.User" user "User.Drawings")
		(19 "Cmts.User" user "User.Comments")
		(21 "Eco1.User" user "User.Eco1")
		(23 "Eco2.User" user "User.Eco2")
		(25 "Edge.Cuts" user "Board Geometry/Outline")
		(27 "Margin" user)
		(31 "F.CrtYd" user "Package Geometry/Place Bound Top")
		(29 "B.CrtYd" user "Package Geometry/Place Bound Bottom")
		(35 "F.Fab" user "Ref Des/Assembly Top")
		(33 "B.Fab" user "Ref Des/Assembly Bottom")
	)
	(footprint ""
		(layer "F.Cu")
		(at 78.907894 -31.764986 -90)
		(property "Reference" "D4"
			(at 4.079748 -7.092442 90)
			(unlocked yes)
			(layer "F.SilkS")
			(effects
				(font
					(size 0.7874 0.5842)
					(thickness 0.1524)
				)
				(justify left)
			)
		)
		(property "Value" ""
			(at 0 0 270)
			(layer "F.Fab")
			(effects
				(font
					(size 1.27 1.27)
				)
			)
		)
		(duplicate_pad_numbers_are_jumpers no)
		(fp_line
			(start -1.3208 0.5588)
			(end -1.3208 -0.5588)
			(stroke
				(width 0.1524)
				(type default)
			)
			(layer "F.SilkS")
		)
		(fp_line
			(start 1.3208 0.5588)
			(end -1.3208 0.5588)
			(stroke
				(width 0.1524)
				(type default)
			)
			(layer "F.SilkS")
		)
		(fp_line
			(start 1.6256 0.5588)
			(end 1.6256 -0.5588)
			(stroke
				(width 0.1524)
				(type default)
			)
			(layer "F.SilkS")
		)
		(fp_line
			(start 1.778 0.5588)
			(end 1.3208 0.5588)
			(stroke
				(width 0.1524)
				(type default)
			)
			(layer "F.SilkS")
		)
		(fp_line
			(start -1.3208 -0.5588)
			(end 1.3208 -0.5588)
			(stroke
				(width 0.1524)
				(type default)
			)
			(layer "F.SilkS")
		)
		(fp_line
			(start 1.3208 -0.5588)
			(end 1.3208 0.5588)
			(stroke
				(width 0.1524)
				(type default)
			)
			(layer "F.SilkS")
		)
		(fp_line
			(start 1.4732 -0.5588)
			(end 1.4732 0.5588)
			(stroke
				(width 0.1524)
				(type default)
			)
			(layer "F.SilkS")
		)
		(fp_line
			(start 1.778 -0.5588)
			(end 1.778 0.5588)
			(stroke
				(width 0.1524)
				(type default)
			)
			(layer "F.SilkS")
		)
		(fp_line
			(start 1.778 -0.5588)
			(end 1.3208 -0.5588)
			(stroke
				(width 0.1524)
				(type default)
			)
			(layer "F.SilkS")
		)
		(fp_line
			(start -0.8001 0.40005)
			(end -0.8001 -0.40005)
			(stroke
				(width 0.1)
				(type default)
			)
			(layer "F.Fab")
		)
		(fp_line
			(start 0.8001 0.40005)
			(end -0.8001 0.40005)
			(stroke
				(width 0.1)
				(type default)
			)
			(layer "F.Fab")
		)
		(fp_line
			(start -0.8001 -0.40005)
			(end 0.8001 -0.40005)
			(stroke
				(width 0.1)
				(type default)
			)
			(layer "F.Fab")
		)
		(fp_line
			(start 0.8001 -0.40005)
			(end 0.8001 0.40005)
			(stroke
				(width 0.1)
				(type default)
			)
			(layer "F.Fab")
		)
		(fp_text user "-"
			(at 0.642874 -1.107948 270)
			(unlocked yes)
			(layer "F.SilkS")
			(effects
				(font
					(size 1.905 1.4224)
					(thickness 0.1524)
				)
				(justify left)
			)
		)
		(fp_text user "+"
			(at -1.606804 -1.380998 270)
			(unlocked yes)
			(layer "F.SilkS")
			(effects
				(font
					(size 1.905 1.4224)
					(thickness 0.1524)
				)
				(justify left)
			)
		)
		(fp_text user "+"
			(at -2.5654 -0.22225 270)
			(unlocked yes)
			(layer "F.Fab")
			(effects
				(font
					(size 1.905 1.4224)
					(thickness 0.1524)
				)
				(justify left)
			)
		)
		(fp_text user "-"
			(at 1.6256 -0.22225 270)
			(unlocked yes)
			(layer "F.Fab")
			(effects
				(font
					(size 1.905 1.4224)
					(thickness 0.1524)
				)
				(justify left)
			)
		)
		(pad "A" smd rect
			(at -0.750062 0 270)
			(size 0.8128 0.8128)
			(layers "F.Cu" "F.Mask" "F.Paste")
			(net "LED_POSTCODE_4_R")
		)
		(pad "C" smd rect
			(at 0.750062 0 270)
			(size 0.8128 0.8128)
			(layers "F.Cu" "F.Mask" "F.Paste")
			(net "GND")
		)
	)
	(footprint ""
		(layer "F.Cu")
		(at -7.6454 -66.929 180)
		(property "Reference" "DB4"
			(at -1.0668 -5.826252 0)
			(unlocked yes)
			(layer "F.SilkS")
			(effects
				(font
					(size 0.7874 0.5842)
					(thickness 0.1524)
				)
				(justify left)
			)
		)
		(property "Value" ""
			(at 0 0 180)
			(layer "F.Fab")
			(effects
				(font
					(size 1.27 1.27)
				)
			)
		)
		(duplicate_pad_numbers_are_jumpers no)
		(fp_line
			(start 3.330702 -4.771136)
			(end 0 4.011168)
			(stroke
				(width 0.1524)
				(type default)
			)
			(layer "F.SilkS")
		)
		(fp_line
			(start 0 4.011168)
			(end -3.330702 -4.771136)
			(stroke
				(width 0.1524)
				(type default)
			)
			(layer "F.SilkS")
		)
		(fp_line
			(start -3.330702 -4.771136)
			(end 3.330702 -4.771136)
			(stroke
				(width 0.1524)
				(type default)
			)
			(layer "F.SilkS")
		)
		(fp_line
			(start 3.330702 -4.771136)
			(end 0 4.011168)
			(stroke
				(width 0.1)
				(type default)
			)
			(layer "F.Fab")
		)
		(fp_line
			(start 0 4.011168)
			(end -3.330702 -4.771136)
			(stroke
				(width 0.1)
				(type default)
			)
			(layer "F.Fab")
		)
		(fp_line
			(start -3.330702 -4.771136)
			(end 3.330702 -4.771136)
			(stroke
				(width 0.1)
				(type default)
			)
			(layer "F.Fab")
		)
		(pad "1" thru_hole circle
			(at 0 0 180)
			(size 2.159 2.159)
			(drill 1.7018)
			(layers "*.Cu" "*.Mask")
			(remove_unused_layers no)
			(net "T_GND")
			(clearance 0.0254)
			(thermal_gap 0.0254)
		)
		(pad "2" thru_hole circle
			(at -1.27 -3.348736 180)
			(size 2.159 2.159)
			(drill 1.7018)
			(layers "*.Cu" "*.Mask")
			(remove_unused_layers no)
			(net "TDR_SE_50_OHM_IN3")
			(clearance 0.0254)
			(thermal_gap 0.0254)
		)
		(pad "3" thru_hole circle
			(at 1.27 -3.348736 180)
			(size 2.159 2.159)
			(drill 1.7018)
			(layers "*.Cu" "*.Mask")
			(remove_unused_layers no)
			(net "TDR_SE_50_OHM_IN3")
			(clearance 0.0254)
			(thermal_gap 0.0254)
		)
	)
	(footprint ""
		(layer "F.Cu")
		(at 53.388006 -30.867604 90)
		(property "Reference" "R261"
			(at 0 0 90)
			(layer "F.SilkS")
			(hide yes)
			(effects
				(font
					(size 1.27 1.27)
				)
			)
		)
		(property "Value" ""
			(at 0 0 90)
			(layer "F.Fab")
			(effects
				(font
					(size 1.27 1.27)
				)
			)
		)
		(duplicate_pad_numbers_are_jumpers no)
		(fp_line
			(start 0.7874 -0.4064)
			(end 0.7874 0.4064)
			(stroke
				(width 0.1524)
				(type default)
			)
			(layer "F.SilkS")
		)
		(fp_line
			(start -0.7874 -0.4064)
			(end 0.7874 -0.4064)
			(stroke
				(width 0.1524)
				(type default)
			)
			(layer "F.SilkS")
		)
		(fp_line
			(start 0.7874 0.4064)
			(end -0.7874 0.4064)
			(stroke
				(width 0.1524)
				(type default)
			)
			(layer "F.SilkS")
		)
		(fp_line
			(start -0.7874 0.4064)
			(end -0.7874 -0.4064)
			(stroke
				(width 0.1524)
				(type default)
			)
			(layer "F.SilkS")
		)
		(fp_line
			(start -0.12065 -0.305054)
			(end -0.12065 -0.2794)
			(stroke
				(width 0.1)
				(type default)
			)
			(layer "F.Fab")
		)
		(fp_line
			(start -0.67945 -0.305054)
			(end -0.12065 -0.305054)
			(stroke
				(width 0.1)
				(type default)
			)
			(layer "F.Fab")
		)
		(fp_line
			(start 0.67945 -0.3048)
			(end 0.67945 0.3048)
			(stroke
				(width 0.1)
				(type default)
			)
			(layer "F.Fab")
		)
		(fp_line
			(start 0.12065 -0.3048)
			(end 0.67945 -0.3048)
			(stroke
				(width 0.1)
				(type default)
			)
			(layer "F.Fab")
		)
		(fp_line
			(start 0.12065 -0.2794)
			(end 0.12065 -0.3048)
			(stroke
				(width 0.1)
				(type default)
			)
			(layer "F.Fab")
		)
		(fp_line
			(start -0.12065 -0.2794)
			(end 0.12065 -0.2794)
			(stroke
				(width 0.1)
				(type default)
			)
			(layer "F.Fab")
		)
		(fp_line
			(start 0.120396 0.2794)
			(end -0.12065 0.2794)
			(stroke
				(width 0.1)
				(type default)
			)
			(layer "F.Fab")
		)
		(fp_line
			(start -0.12065 0.2794)
			(end -0.12065 0.3048)
			(stroke
				(width 0.1)
				(type default)
			)
			(layer "F.Fab")
		)
		(fp_line
			(start 0.67945 0.3048)
			(end 0.120396 0.3048)
			(stroke
				(width 0.1)
				(type default)
			)
			(layer "F.Fab")
		)
		(fp_line
			(start 0.120396 0.3048)
			(end 0.120396 0.2794)
			(stroke
				(width 0.1)
				(type default)
			)
			(layer "F.Fab")
		)
		(fp_line
			(start -0.12065 0.3048)
			(end -0.67945 0.3048)
			(stroke
				(width 0.1)
				(type default)
			)
			(layer "F.Fab")
		)
		(fp_line
			(start -0.67945 0.3048)
			(end -0.67945 -0.305054)
			(stroke
				(width 0.1)
				(type default)
			)
			(layer "F.Fab")
		)
		(pad "1" smd circle
			(at -0.40005 0 90)
			(size 0 0)
			(layers "F.Cu" "F.Mask" "F.Paste")
			(net "P3V3_AUX")
		)
		(pad "2" smd circle
			(at 0.40005 0 90)
			(size 0 0)
			(layers "F.Cu" "F.Mask" "F.Paste")
			(net "SMB_BMC_MM9_SDA")
		)
	)
	(footprint ""
		(layer "F.Cu")
		(at 10.287 -98.298 -90)
		(property "Reference" "R518"
			(at 0 0 270)
			(layer "F.SilkS")
			(hide yes)
			(effects
				(font
					(size 1.27 1.27)
				)
			)
		)
		(property "Value" ""
			(at 0 0 270)
			(layer "F.Fab")
			(effects
				(font
					(size 1.27 1.27)
				)
			)
		)
		(duplicate_pad_numbers_are_jumpers no)
		(fp_line
			(start -0.7874 0.4064)
			(end -0.7874 -0.4064)
			(stroke
				(width 0.1524)
				(type default)
			)
			(layer "F.SilkS")
		)
		(fp_line
			(start 0.7874 0.4064)
			(end -0.7874 0.4064)
			(stroke
				(width 0.1524)
				(type default)
			)
			(layer "F.SilkS")
		)
		(fp_line
			(start -0.7874 -0.4064)
			(end 0.7874 -0.4064)
			(stroke
				(width 0.1524)
				(type default)
			)
			(layer "F.SilkS")
		)
		(fp_line
			(start 0.7874 -0.4064)
			(end 0.7874 0.4064)
			(stroke
				(width 0.1524)
				(type default)
			)
			(layer "F.SilkS")
		)
		(fp_line
			(start -0.67945 0.3048)
			(end -0.67945 -0.305054)
			(stroke
				(width 0.1)
				(type default)
			)
			(layer "F.Fab")
		)
		(fp_line
			(start -0.12065 0.3048)
			(end -0.67945 0.3048)
			(stroke
				(width 0.1)
				(type default)
			)
			(layer "F.Fab")
		)
		(fp_line
			(start 0.120396 0.3048)
			(end 0.120396 0.2794)
			(stroke
				(width 0.1)
				(type default)
			)
			(layer "F.Fab")
		)
		(fp_line
			(start 0.67945 0.3048)
			(end 0.120396 0.3048)
			(stroke
				(width 0.1)
				(type default)
			)
			(layer "F.Fab")
		)
		(fp_line
			(start -0.12065 0.2794)
			(end -0.12065 0.3048)
			(stroke
				(width 0.1)
				(type default)
			)
			(layer "F.Fab")
		)
		(fp_line
			(start 0.120396 0.2794)
			(end -0.12065 0.2794)
			(stroke
				(width 0.1)
				(type default)
			)
			(layer "F.Fab")
		)
		(fp_line
			(start -0.12065 -0.2794)
			(end 0.12065 -0.2794)
			(stroke
				(width 0.1)
				(type default)
			)
			(layer "F.Fab")
		)
		(fp_line
			(start 0.12065 -0.2794)
			(end 0.12065 -0.3048)
			(stroke
				(width 0.1)
				(type default)
			)
			(layer "F.Fab")
		)
		(fp_line
			(start 0.12065 -0.3048)
			(end 0.67945 -0.3048)
			(stroke
				(width 0.1)
				(type default)
			)
			(layer "F.Fab")
		)
		(fp_line
			(start 0.67945 -0.3048)
			(end 0.67945 0.3048)
			(stroke
				(width 0.1)
				(type default)
			)
			(layer "F.Fab")
		)
		(fp_line
			(start -0.67945 -0.305054)
			(end -0.12065 -0.305054)
			(stroke
				(width 0.1)
				(type default)
			)
			(layer "F.Fab")
		)
		(fp_line
			(start -0.12065 -0.305054)
			(end -0.12065 -0.2794)
			(stroke
				(width 0.1)
				(type default)
			)
			(layer "F.Fab")
		)
		(pad "1" smd circle
			(at -0.40005 0 270)
			(size 0 0)
			(layers "F.Cu" "F.Mask" "F.Paste")
			(net "JTAG_SCM_PLD_R1_JTAGEN")
		)
		(pad "2" smd circle
			(at 0.40005 0 270)
			(size 0 0)
			(layers "F.Cu" "F.Mask" "F.Paste")
			(net "JTAG_SCM_PLD_JTAGEN")
		)
	)
	(footprint ""
		(layer "F.Cu")
		(at 14.113002 -106.33837)
		(property "Reference" "U13"
			(at 1.279398 1.81864 0)
			(unlocked yes)
			(layer "F.SilkS")
			(effects
				(font
					(size 0.7874 0.5842)
					(thickness 0.1524)
				)
				(justify left)
			)
		)
		(property "Value" ""
			(at 0 0 0)
			(layer "F.Fab")
			(effects
				(font
					(size 1.27 1.27)
				)
			)
		)
		(duplicate_pad_numbers_are_jumpers no)
		(fp_line
			(start -1.33096 -1.100074)
			(end -0.381 -1.100074)
			(stroke
				(width 0.1524)
				(type default)
			)
			(layer "F.SilkS")
		)
		(fp_line
			(start -1.33096 1.100074)
			(end -1.33096 -1.100074)
			(stroke
				(width 0.1524)
				(type default)
			)
			(layer "F.SilkS")
		)
		(fp_line
			(start -0.381 -1.100074)
			(end 0 -0.649986)
			(stroke
				(width 0.1524)
				(type default)
			)
			(layer "F.SilkS")
		)
		(fp_line
			(start 0 -0.649986)
			(end 0.381 -1.100074)
			(stroke
				(width 0.1524)
				(type default)
			)
			(layer "F.SilkS")
		)
		(fp_line
			(start 0.381 -1.100074)
			(end 1.33096 -1.100074)
			(stroke
				(width 0.1524)
				(type default)
			)
			(layer "F.SilkS")
		)
		(fp_line
			(start 1.33096 -1.100074)
			(end 1.33096 1.100074)
			(stroke
				(width 0.1524)
				(type default)
			)
			(layer "F.SilkS")
		)
		(fp_line
			(start 1.33096 1.100074)
			(end -1.33096 1.100074)
			(stroke
				(width 0.1524)
				(type default)
			)
			(layer "F.SilkS")
		)
		(fp_poly
			(pts
				(xy -2.209292 -0.902462) (xy -2.209292 -0.394462) (xy -1.447292 -0.648462)
			)
			(stroke
				(width 0)
				(type default)
			)
			(fill yes)
			(layer "F.SilkS")
		)
		(fp_line
			(start -0.674878 -1.100074)
			(end 0.674878 -1.100074)
			(stroke
				(width 0.1)
				(type default)
			)
			(layer "F.Fab")
		)
		(fp_line
			(start -0.674878 1.100074)
			(end -0.674878 -1.100074)
			(stroke
				(width 0.1)
				(type default)
			)
			(layer "F.Fab")
		)
		(fp_line
			(start 0.674878 -1.100074)
			(end 0.674878 1.100074)
			(stroke
				(width 0.1)
				(type default)
			)
			(layer "F.Fab")
		)
		(fp_line
			(start 0.674878 1.100074)
			(end -0.674878 1.100074)
			(stroke
				(width 0.1)
				(type default)
			)
			(layer "F.Fab")
		)
		(fp_poly
			(pts
				(xy -2.209292 -0.902462) (xy -2.209292 -0.394462) (xy -1.447292 -0.648462)
			)
			(stroke
				(width 0)
				(type default)
			)
			(fill yes)
			(layer "F.Fab")
		)
		(pad "1" smd rect
			(at -0.94996 -0.649986 90)
			(size 0.4064 0.508)
			(layers "F.Cu" "F.Mask" "F.Paste")
			(net "Net_317")
		)
		(pad "2" smd rect
			(at -0.94996 0 90)
			(size 0.4064 0.508)
			(layers "F.Cu" "F.Mask" "F.Paste")
			(net "RST_BMC_SRST_BUF_R1_N")
		)
		(pad "3" smd rect
			(at -0.94996 0.649986 90)
			(size 0.4064 0.508)
			(layers "F.Cu" "F.Mask" "F.Paste")
			(net "GND")
		)
		(pad "4" smd rect
			(at 0.94996 0.649986 90)
			(size 0.4064 0.508)
			(layers "F.Cu" "F.Mask" "F.Paste")
			(net "RST_BMC_EXTRST_R1_N")
		)
		(pad "5" smd rect
			(at 0.94996 -0.649986 90)
			(size 0.4064 0.508)
			(layers "F.Cu" "F.Mask" "F.Paste")
			(net "P3V3_AUX")
		)
	)
	(footprint ""
		(layer "F.Cu")
		(at 39.095172 -83.816952 -90)
		(property "Reference" "R655"
			(at 0 0 270)
			(layer "F.SilkS")
			(hide yes)
			(effects
				(font
					(size 1.27 1.27)
				)
			)
		)
		(property "Value" ""
			(at 0 0 270)
			(layer "F.Fab")
			(effects
				(font
					(size 1.27 1.27)
				)
			)
		)
		(duplicate_pad_numbers_are_jumpers no)
		(fp_line
			(start -0.7874 0.4064)
			(end -0.7874 -0.4064)
			(stroke
				(width 0.1524)
				(type default)
			)
			(layer "F.SilkS")
		)
		(fp_line
			(start 0.7874 0.4064)
			(end -0.7874 0.4064)
			(stroke
				(width 0.1524)
				(type default)
			)
			(layer "F.SilkS")
		)
		(fp_line
			(start -0.7874 -0.4064)
			(end 0.7874 -0.4064)
			(stroke
				(width 0.1524)
				(type default)
			)
			(layer "F.SilkS")
		)
		(fp_line
			(start 0.7874 -0.4064)
			(end 0.7874 0.4064)
			(stroke
				(width 0.1524)
				(type default)
			)
			(layer "F.SilkS")
		)
		(fp_line
			(start -0.67945 0.3048)
			(end -0.67945 -0.305054)
			(stroke
				(width 0.1)
				(type default)
			)
			(layer "F.Fab")
		)
		(fp_line
			(start -0.12065 0.3048)
			(end -0.67945 0.3048)
			(stroke
				(width 0.1)
				(type default)
			)
			(layer "F.Fab")
		)
		(fp_line
			(start 0.120396 0.3048)
			(end 0.120396 0.2794)
			(stroke
				(width 0.1)
				(type default)
			)
			(layer "F.Fab")
		)
		(fp_line
			(start 0.67945 0.3048)
			(end 0.120396 0.3048)
			(stroke
				(width 0.1)
				(type default)
			)
			(layer "F.Fab")
		)
		(fp_line
			(start -0.12065 0.2794)
			(end -0.12065 0.3048)
			(stroke
				(width 0.1)
				(type default)
			)
			(layer "F.Fab")
		)
		(fp_line
			(start 0.120396 0.2794)
			(end -0.12065 0.2794)
			(stroke
				(width 0.1)
				(type default)
			)
			(layer "F.Fab")
		)
		(fp_line
			(start -0.12065 -0.2794)
			(end 0.12065 -0.2794)
			(stroke
				(width 0.1)
				(type default)
			)
			(layer "F.Fab")
		)
		(fp_line
			(start 0.12065 -0.2794)
			(end 0.12065 -0.3048)
			(stroke
				(width 0.1)
				(type default)
			)
			(layer "F.Fab")
		)
		(fp_line
			(start 0.12065 -0.3048)
			(end 0.67945 -0.3048)
			(stroke
				(width 0.1)
				(type default)
			)
			(layer "F.Fab")
		)
		(fp_line
			(start 0.67945 -0.3048)
			(end 0.67945 0.3048)
			(stroke
				(width 0.1)
				(type default)
			)
			(layer "F.Fab")
		)
		(fp_line
			(start -0.67945 -0.305054)
			(end -0.12065 -0.305054)
			(stroke
				(width 0.1)
				(type default)
			)
			(layer "F.Fab")
		)
		(fp_line
			(start -0.12065 -0.305054)
			(end -0.12065 -0.2794)
			(stroke
				(width 0.1)
				(type default)
			)
			(layer "F.Fab")
		)
		(pad "1" smd circle
			(at -0.40005 0 270)
			(size 0 0)
			(layers "F.Cu" "F.Mask" "F.Paste")
			(net "P3V3_AUX")
		)
		(pad "2" smd circle
			(at 0.40005 0 270)
			(size 0 0)
			(layers "F.Cu" "F.Mask" "F.Paste")
			(net "EMMC_DT0_R")
		)
	)
)
